# SCM (Grand Teton) — schematic netlist excerpt (pin names and nets, part order shuffled) for the footprints in the layout excerpt that follows; sources: Cadence DE-HDL packaged netlist, KiCad conversion of 12092022_DA0F0TMDCD0_F0T_Management_Board_D_brd_V3_OCP.brd

R262  Q_RES  10K 1% CHIP  pkg 0402LF  page 27 : A = P3V3_AUX ; B = SMB_BMC_MM10_SCL
R117  Q_RES  4.7K 1% EMPTY  pkg 0402LF  page 12 : A = PGPPA_BMC_AUX ; B = RST_BMC_LPC_ESPI_N

(kicad_pcb
	(version 20260206)
	(generator "pcbnew")
	(generator_version "10.0")
	(general
		(thickness 1.6)
		(legacy_teardrops no)
	)
	(paper "A4")
	(title_block
		(title "12092022_DA0F0TMDCD0_F0T_Management_Board_D_brd_V3_OCP.brd")
		(comment 1 "Grand Teton / footprints 938-939 of 1440")
	)
	(layers
		(0 "F.Cu" signal "TOP")
		(4 "In1.Cu" signal "GND")
		(6 "In2.Cu" signal "IN1")
		(8 "In3.Cu" signal "GND1")
		(10 "In4.Cu" signal "IN2")
		(12 "In5.Cu" signal "VCC")
		(14 "In6.Cu" signal "VCC1")
		(16 "In7.Cu" signal "IN3")
		(18 "In8.Cu" signal "GND2")
		(20 "In9.Cu" signal "IN4")
		(22 "In10.Cu" signal "GND3")
		(2 "B.Cu" signal "BOTTOM")
		(9 "F.Adhes" user "F.Adhesive")
		(11 "B.Adhes" user "B.Adhesive")
		(13 "F.Paste" user "Package Geometry/Pastemask Top")
		(15 "B.Paste" user "Package Geometry/Pastemask Bottom")
		(5 "F.SilkS" user "Ref Des/Silkscreen Top")
		(7 "B.SilkS" user "Ref Des/Silkscreen Bottom")
		(1 "F.Mask" user "Board Geometry/Soldermask Top")
		(3 "B.Mask" user "Board Geometry/Soldermask Bottom")
		(17 "Dwgs.User" user "User.Drawings")
		(19 "Cmts.User" user "User.Comments")
		(21 "Eco1.User" user "User.Eco1")
		(23 "Eco2.User" user "User.Eco2")
		(25 "Edge.Cuts" user "Board Geometry/Outline")
		(27 "Margin" user)
		(31 "F.CrtYd" user "Package Geometry/Place Bound Top")
		(29 "B.CrtYd" user "Package Geometry/Place Bound Bottom")
		(35 "F.Fab" user "Ref Des/Assembly Top")
		(33 "B.Fab" user "Ref Des/Assembly Bottom")
	)
	(footprint ""
		(layer "B.Cu")
		(at 63.964058 -70.296024 180)
		(property "Reference" "R117"
			(at 0 0 0)
			(layer "B.SilkS")
			(hide yes)
			(effects
				(font
					(size 1.27 1.27)
				)
				(justify mirror)
			)
		)
		(property "Value" ""
			(at 0 0 0)
			(layer "B.Fab")
			(effects
				(font
					(size 1.27 1.27)
				)
				(justify mirror)
			)
		)
		(duplicate_pad_numbers_are_jumpers no)
		(fp_line
			(start 0.7874 0.4064)
			(end 0.7874 -0.4064)
			(stroke
				(width 0.1524)
				(type default)
			)
			(layer "B.SilkS")
		)
		(fp_line
			(start 0.7874 -0.4064)
			(end -0.7874 -0.4064)
			(stroke
				(width 0.1524)
				(type default)
			)
			(layer "B.SilkS")
		)
		(fp_line
			(start -0.7874 0.4064)
			(end 0.7874 0.4064)
			(stroke
				(width 0.1524)
				(type default)
			)
			(layer "B.SilkS")
		)
		(fp_line
			(start -0.7874 -0.4064)
			(end -0.7874 0.4064)
			(stroke
				(width 0.1524)
				(type default)
			)
			(layer "B.SilkS")
		)
		(fp_line
			(start 0.67945 0.3048)
			(end 0.67945 -0.305054)
			(stroke
				(width 0.1)
				(type default)
			)
			(layer "B.Fab")
		)
		(fp_line
			(start 0.67945 -0.305054)
			(end 0.12065 -0.305054)
			(stroke
				(width 0.1)
				(type default)
			)
			(layer "B.Fab")
		)
		(fp_line
			(start 0.12065 0.3048)
			(end 0.67945 0.3048)
			(stroke
				(width 0.1)
				(type default)
			)
			(layer "B.Fab")
		)
		(fp_line
			(start 0.12065 0.2794)
			(end 0.12065 0.3048)
			(stroke
				(width 0.1)
				(type default)
			)
			(layer "B.Fab")
		)
		(fp_line
			(start 0.12065 -0.2794)
			(end -0.12065 -0.2794)
			(stroke
				(width 0.1)
				(type default)
			)
			(layer "B.Fab")
		)
		(fp_line
			(start 0.12065 -0.305054)
			(end 0.12065 -0.2794)
			(stroke
				(width 0.1)
				(type default)
			)
			(layer "B.Fab")
		)
		(fp_line
			(start -0.120396 0.3048)
			(end -0.120396 0.2794)
			(stroke
				(width 0.1)
				(type default)
			)
			(layer "B.Fab")
		)
		(fp_line
			(start -0.120396 0.2794)
			(end 0.12065 0.2794)
			(stroke
				(width 0.1)
				(type default)
			)
			(layer "B.Fab")
		)
		(fp_line
			(start -0.12065 -0.2794)
			(end -0.12065 -0.3048)
			(stroke
				(width 0.1)
				(type default)
			)
			(layer "B.Fab")
		)
		(fp_line
			(start -0.12065 -0.3048)
			(end -0.67945 -0.3048)
			(stroke
				(width 0.1)
				(type default)
			)
			(layer "B.Fab")
		)
		(fp_line
			(start -0.67945 0.3048)
			(end -0.120396 0.3048)
			(stroke
				(width 0.1)
				(type default)
			)
			(layer "B.Fab")
		)
		(fp_line
			(start -0.67945 -0.3048)
			(end -0.67945 0.3048)
			(stroke
				(width 0.1)
				(type default)
			)
			(layer "B.Fab")
		)
		(pad "1" smd circle
			(at 0.40005 0)
			(size 0 0)
			(layers "B.Cu" "B.Mask" "B.Paste")
			(net "PGPPA_BMC_AUX")
		)
		(pad "2" smd circle
			(at -0.40005 0)
			(size 0 0)
			(layers "B.Cu" "B.Mask" "B.Paste")
			(net "RST_BMC_LPC_ESPI_N")
		)
	)
	(footprint ""
		(layer "B.Cu")
		(at 54.684676 -30.867604 -90)
		(property "Reference" "R262"
			(at 0 0 90)
			(layer "B.SilkS")
			(hide yes)
			(effects
				(font
					(size 1.27 1.27)
				)
				(justify mirror)
			)
		)
		(property "Value" ""
			(at 0 0 90)
			(layer "B.Fab")
			(effects
				(font
					(size 1.27 1.27)
				)
				(justify mirror)
			)
		)
		(duplicate_pad_numbers_are_jumpers no)
		(fp_line
			(start -0.7874 0.4064)
			(end 0.7874 0.4064)
			(stroke
				(width 0.1524)
				(type default)
			)
			(layer "B.SilkS")
		)
		(fp_line
			(start 0.7874 0.4064)
			(end 0.7874 -0.4064)
			(stroke
				(width 0.1524)
				(type default)
			)
			(layer "B.SilkS")
		)
		(fp_line
			(start -0.7874 -0.4064)
			(end -0.7874 0.4064)
			(stroke
				(width 0.1524)
				(type default)
			)
			(layer "B.SilkS")
		)
		(fp_line
			(start 0.7874 -0.4064)
			(end -0.7874 -0.4064)
			(stroke
				(width 0.1524)
				(type default)
			)
			(layer "B.SilkS")
		)
		(fp_line
			(start -0.67945 0.3048)
			(end -0.120396 0.3048)
			(stroke
				(width 0.1)
				(type default)
			)
			(layer "B.Fab")
		)
		(fp_line
			(start -0.120396 0.3048)
			(end -0.120396 0.2794)
			(stroke
				(width 0.1)
				(type default)
			)
			(layer "B.Fab")
		)
		(fp_line
			(start 0.12065 0.3048)
			(end 0.67945 0.3048)
			(stroke
				(width 0.1)
				(type default)
			)
			(layer "B.Fab")
		)
		(fp_line
			(start 0.67945 0.3048)
			(end 0.67945 -0.305054)
			(stroke
				(width 0.1)
				(type default)
			)
			(layer "B.Fab")
		)
		(fp_line
			(start -0.120396 0.2794)
			(end 0.12065 0.2794)
			(stroke
				(width 0.1)
				(type default)
			)
			(layer "B.Fab")
		)
		(fp_line
			(start 0.12065 0.2794)
			(end 0.12065 0.3048)
			(stroke
				(width 0.1)
				(type default)
			)
			(layer "B.Fab")
		)
		(fp_line
			(start -0.12065 -0.2794)
			(end -0.12065 -0.3048)
			(stroke
				(width 0.1)
				(type default)
			)
			(layer "B.Fab")
		)
		(fp_line
			(start 0.12065 -0.2794)
			(end -0.12065 -0.2794)
			(stroke
				(width 0.1)
				(type default)
			)
			(layer "B.Fab")
		)
		(fp_line
			(start -0.67945 -0.3048)
			(end -0.67945 0.3048)
			(stroke
				(width 0.1)
				(type default)
			)
			(layer "B.Fab")
		)
		(fp_line
			(start -0.12065 -0.3048)
			(end -0.67945 -0.3048)
			(stroke
				(width 0.1)
				(type default)
			)
			(layer "B.Fab")
		)
		(fp_line
			(start 0.12065 -0.305054)
			(end 0.12065 -0.2794)
			(stroke
				(width 0.1)
				(type default)
			)
			(layer "B.Fab")
		)
		(fp_line
			(start 0.67945 -0.305054)
			(end 0.12065 -0.305054)
			(stroke
				(width 0.1)
				(type default)
			)
			(layer "B.Fab")
		)
		(pad "1" smd circle
			(at 0.40005 0 90)
			(size 0 0)
			(layers "B.Cu" "B.Mask" "B.Paste")
			(net "P3V3_AUX")
		)
		(pad "2" smd circle
			(at -0.40005 0 90)
			(size 0 0)
			(layers "B.Cu" "B.Mask" "B.Paste")
			(net "SMB_BMC_MM10_SCL")
		)
	)
)
